(kicad_pcb
	(version 20241229)
	(generator "pcbnew")
	(generator_version "9.0")
	(general
		(thickness 1.6)
		(legacy_teardrops no)
	)
	(paper "A4")
	(title_block
		(title "OCuLink to PCIe adapter")
		(date "2025-06-18")
		(rev "1.0.0")
		(company "Antmicro Ltd")
		(comment 1 "www.antmicro.com")
		(comment 9 "footprints 102-105 of 159")
	)
	(layers
		(0 "F.Cu" signal)
		(4 "In1.Cu" signal)
		(6 "In2.Cu" signal)
		(2 "B.Cu" signal)
		(9 "F.Adhes" user "F.Adhesive")
		(11 "B.Adhes" user "B.Adhesive")
		(13 "F.Paste" user)
		(15 "B.Paste" user)
		(5 "F.SilkS" user "F.Silkscreen")
		(7 "B.SilkS" user "B.Silkscreen")
		(1 "F.Mask" user)
		(3 "B.Mask" user)
		(17 "Dwgs.User" user "User.Drawings")
		(19 "Cmts.User" user "User.Comments")
		(21 "Eco1.User" user "User.Eco1")
		(23 "Eco2.User" user "User.Eco2")
		(25 "Edge.Cuts" user)
		(27 "Margin" user)
		(31 "F.CrtYd" user "F.Courtyard")
		(29 "B.CrtYd" user "B.Courtyard")
		(35 "F.Fab" user)
		(33 "B.Fab" user)
	)
	(footprint "antmicro-footprints:R_0603_1608Metric"
		(layer "F.Cu")
		(at 117.5 138.6 -90)
		(descr "Resistor SMD 0603")
		(tags "resistor SMD 0603")
		(property "Reference" "R53"
			(at -1.1 1.7 90)
			(layer "F.SilkS")
			(effects
				(font
					(size 0.7 0.7)
					(thickness 0.15)
				)
				(justify right top)
			)
		)
		(property "Value" "R_0R_22.4A_0603"
			(at 0 1.6 90)
			(layer "F.Fab")
			(effects
				(font
					(size 0.7 0.7)
					(thickness 0.15)
				)
				(justify right top)
			)
		)
		(property "Datasheet" "https://fscdn.rohm.com/en/products/databook/datasheet/passive/resistor/chip_resistor/pmr-jpw-e.pdf"
			(at 0 0 90)
			(layer "F.Fab")
			(hide yes)
			(effects
				(font
					(size 1.27 1.27)
					(thickness 0.15)
				)
			)
		)
		(property "Description" "SMD Chip Resistor"
			(at 0 0 90)
			(layer "F.Fab")
			(hide yes)
			(effects
				(font
					(size 1.27 1.27)
					(thickness 0.15)
				)
			)
		)
		(property "MPN" "PMR03EZPJ000"
			(at 0 0 270)
			(unlocked yes)
			(layer "F.Fab")
			(hide yes)
			(effects
				(font
					(size 1 1)
					(thickness 0.15)
				)
			)
		)
		(property "Manufacturer" "ROHM Semiconductor"
			(at 0 0 270)
			(unlocked yes)
			(layer "F.Fab")
			(hide yes)
			(effects
				(font
					(size 1 1)
					(thickness 0.15)
				)
			)
		)
		(property "Val" "0R"
			(at 0 0 270)
			(unlocked yes)
			(layer "F.Fab")
			(hide yes)
			(effects
				(font
					(size 1 1)
					(thickness 0.15)
				)
			)
		)
		(property "Max. Curr." "22.4A"
			(at 0 0 270)
			(unlocked yes)
			(layer "F.Fab")
			(hide yes)
			(effects
				(font
					(size 1 1)
					(thickness 0.15)
				)
			)
		)
		(property "Author" "Antmicro"
			(at 0 0 270)
			(unlocked yes)
			(layer "F.Fab")
			(hide yes)
			(effects
				(font
					(size 1 1)
					(thickness 0.15)
				)
			)
		)
		(property "License" "Apache-2.0"
			(at 0 0 270)
			(unlocked yes)
			(layer "F.Fab")
			(hide yes)
			(effects
				(font
					(size 1 1)
					(thickness 0.15)
				)
			)
		)
		(property "Tolerance" "template_tolerance"
			(at 0 0 270)
			(unlocked yes)
			(layer "F.Fab")
			(hide yes)
			(effects
				(font
					(size 1 1)
					(thickness 0.15)
				)
			)
		)
		(sheetname "/Power/")
		(sheetfile "power.kicad_sch")
		(attr smd exclude_from_bom)
		(fp_line
			(start -0.15 0.4)
			(end 0.15 0.4)
			(stroke
				(width 0.15)
				(type solid)
			)
			(layer "F.SilkS")
		)
		(fp_line
			(start -0.15 -0.4)
			(end 0.15 -0.4)
			(stroke
				(width 0.15)
				(type solid)
			)
			(layer "F.SilkS")
		)
		(fp_rect
			(start -1.25 -0.65)
			(end 1.25 0.65)
			(stroke
				(width 0.05)
				(type solid)
			)
			(fill no)
			(layer "F.CrtYd")
		)
		(fp_rect
			(start -0.8 -0.4)
			(end 0.8 0.4)
			(stroke
				(width 0.15)
				(type solid)
			)
			(fill no)
			(layer "F.Fab")
		)
		(fp_text user "Author: Antmicro"
			(at -1.25 4.9 90)
			(layer "F.Fab")
			(effects
				(font
					(size 0.7 0.7)
					(thickness 0.15)
				)
				(justify right top)
			)
		)
		(fp_text user "${REFERENCE}"
			(at -1.25 3.898 90)
			(layer "F.Fab")
			(effects
				(font
					(size 0.7 0.7)
					(thickness 0.15)
				)
				(justify right top)
			)
		)
		(fp_text user "License: Apache-2.0"
			(at -1.249999 5.9 90)
			(layer "F.Fab")
			(effects
				(font
					(size 0.7 0.7)
					(thickness 0.15)
				)
				(justify right top)
			)
		)
		(pad "1" smd roundrect
			(at -0.7 0 270)
			(size 0.8 1)
			(layers "F.Cu" "F.Mask" "F.Paste")
			(roundrect_rratio 0.2)
			(net 134 "+3V3")
			(pintype "passive")
		)
		(pad "2" smd roundrect
			(at 0.7 0 270)
			(size 0.8 1)
			(layers "F.Cu" "F.Mask" "F.Paste")
			(roundrect_rratio 0.2)
			(net 186 "/Power/3V3_CONV")
			(pintype "passive")
		)
	)
	(footprint "antmicro-footprints:SOT-23-3"
		(layer "F.Cu")
		(at 136.7505 71.35 90)
		(property "Reference" "Q9"
			(at 2.406999 -1.524 90)
			(layer "F.SilkS")
			(effects
				(font
					(size 0.7 0.7)
					(thickness 0.15)
				)
				(justify right top)
			)
		)
		(property "Value" "BSS138-7-F"
			(at -1.9 2.7 90)
			(layer "F.Fab")
			(effects
				(font
					(size 0.7 0.7)
					(thickness 0.15)
				)
				(justify left bottom)
			)
		)
		(property "Datasheet" "https://www.diodes.com/assets/Datasheets/ds30144.pdf"
			(at 0 0 90)
			(layer "F.Fab")
			(hide yes)
			(effects
				(font
					(size 1.27 1.27)
					(thickness 0.15)
				)
			)
		)
		(property "Description" "Power MOSFET, N Channel, 50 V, 200 mA, 1.4 ohm, SOT-23, Surface Mount"
			(at 0 0 90)
			(layer "F.Fab")
			(hide yes)
			(effects
				(font
					(size 1.27 1.27)
					(thickness 0.15)
				)
			)
		)
		(property "MPN" "BSS138-7-F"
			(at 0 0 90)
			(unlocked yes)
			(layer "F.Fab")
			(hide yes)
			(effects
				(font
					(size 1 1)
					(thickness 0.15)
				)
			)
		)
		(property "Manufacturer" "Diodes Incorporated"
			(at 0 0 90)
			(unlocked yes)
			(layer "F.Fab")
			(hide yes)
			(effects
				(font
					(size 1 1)
					(thickness 0.15)
				)
			)
		)
		(property "Author" "Antmicro"
			(at 0 0 90)
			(unlocked yes)
			(layer "F.Fab")
			(hide yes)
			(effects
				(font
					(size 1 1)
					(thickness 0.15)
				)
			)
		)
		(property "License" "Apache-2.0"
			(at 0 0 90)
			(unlocked yes)
			(layer "F.Fab")
			(hide yes)
			(effects
				(font
					(size 1 1)
					(thickness 0.15)
				)
			)
		)
		(sheetname "/USB-PD/")
		(sheetfile "usb-pd.kicad_sch")
		(attr smd)
		(fp_line
			(start 0.7 -1.5)
			(end -0.7 -1.5)
			(stroke
				(width 0.15)
				(type solid)
			)
			(layer "F.SilkS")
		)
		(fp_line
			(start -0.85 -1.35)
			(end -0.7 -1.5)
			(stroke
				(width 0.15)
				(type solid)
			)
			(layer "F.SilkS")
		)
		(fp_line
			(start -1.45 -1.35)
			(end -0.85 -1.35)
			(stroke
				(width 0.15)
				(type solid)
			)
			(layer "F.SilkS")
		)
		(fp_line
			(start 0.7 -0.4)
			(end 0.7 -1.5)
			(stroke
				(width 0.15)
				(type solid)
			)
			(layer "F.SilkS")
		)
		(fp_line
			(start 0.7 0.4)
			(end 0.7 1.5)
			(stroke
				(width 0.15)
				(type solid)
			)
			(layer "F.SilkS")
		)
		(fp_line
			(start 0.7 1.5)
			(end -0.7 1.5)
			(stroke
				(width 0.15)
				(type solid)
			)
			(layer "F.SilkS")
		)
		(fp_line
			(start -0.7 1.5)
			(end -0.7 1.35)
			(stroke
				(width 0.15)
				(type solid)
			)
			(layer "F.SilkS")
		)
		(fp_line
			(start 0.825 -1.6)
			(end 0.825 -0.45)
			(stroke
				(width 0.05)
				(type solid)
			)
			(layer "F.CrtYd")
		)
		(fp_line
			(start -0.9 -1.6)
			(end 0.825 -1.6)
			(stroke
				(width 0.05)
				(type solid)
			)
			(layer "F.CrtYd")
		)
		(fp_line
			(start -0.9 -1.6)
			(end -0.9 -1.4)
			(stroke
				(width 0.05)
				(type solid)
			)
			(layer "F.CrtYd")
		)
		(fp_line
			(start -0.9 -1.4)
			(end -1.75 -1.4)
			(stroke
				(width 0.05)
				(type solid)
			)
			(layer "F.CrtYd")
		)
		(fp_line
			(start -0.85 -0.5)
			(end -1.75 -0.5)
			(stroke
				(width 0.05)
				(type solid)
			)
			(layer "F.CrtYd")
		)
		(fp_line
			(start -1.75 -0.5)
			(end -1.75 -1.4)
			(stroke
				(width 0.05)
				(type solid)
			)
			(layer "F.CrtYd")
		)
		(fp_line
			(start 1.75 -0.45)
			(end 1.75 0.45)
			(stroke
				(width 0.05)
				(type solid)
			)
			(layer "F.CrtYd")
		)
		(fp_line
			(start 0.825 -0.45)
			(end 1.75 -0.45)
			(stroke
				(width 0.05)
				(type solid)
			)
			(layer "F.CrtYd")
		)
		(fp_line
			(start 1.75 0.45)
			(end 0.85 0.45)
			(stroke
				(width 0.05)
				(type solid)
			)
			(layer "F.CrtYd")
		)
		(fp_line
			(start 0.85 0.45)
			(end 0.85 1.65)
			(stroke
				(width 0.05)
				(type solid)
			)
			(layer "F.CrtYd")
		)
		(fp_line
			(start -0.85 0.5)
			(end -0.85 -0.5)
			(stroke
				(width 0.05)
				(type solid)
			)
			(layer "F.CrtYd")
		)
		(fp_line
			(start -1.75 0.5)
			(end -0.85 0.5)
			(stroke
				(width 0.05)
				(type solid)
			)
			(layer "F.CrtYd")
		)
		(fp_line
			(start -0.85 1.4)
			(end -1.75 1.4)
			(stroke
				(width 0.05)
				(type solid)
			)
			(layer "F.CrtYd")
		)
		(fp_line
			(start -1.75 1.4)
			(end -1.75 0.5)
			(stroke
				(width 0.05)
				(type solid)
			)
			(layer "F.CrtYd")
		)
		(fp_line
			(start 0.85 1.65)
			(end -0.85 1.65)
			(stroke
				(width 0.05)
				(type solid)
			)
			(layer "F.CrtYd")
		)
		(fp_line
			(start -0.85 1.65)
			(end -0.85 1.4)
			(stroke
				(width 0.05)
				(type solid)
			)
			(layer "F.CrtYd")
		)
		(fp_line
			(start -0.437 -1.526)
			(end 0.688 -1.526)
			(stroke
				(width 0.15)
				(type solid)
			)
			(layer "F.Fab")
		)
		(fp_line
			(start -0.437 -1.526)
			(end -0.712 -1.325)
			(stroke
				(width 0.15)
				(type solid)
			)
			(layer "F.Fab")
		)
		(fp_line
			(start -0.712 -1.325)
			(end -0.712 1.523)
			(stroke
				(width 0.15)
				(type solid)
			)
			(layer "F.Fab")
		)
		(fp_line
			(start 0.688 1.519)
			(end 0.688 -1.52)
			(stroke
				(width 0.15)
				(type solid)
			)
			(layer "F.Fab")
		)
		(fp_line
			(start -0.712 1.519)
			(end 0.688 1.519)
			(stroke
				(width 0.15)
				(type solid)
			)
			(layer "F.Fab")
		)
		(fp_text user "Author: Antmicro"
			(at -1.837 5.3 90)
			(layer "F.Fab")
			(effects
				(font
					(size 0.7 0.7)
					(thickness 0.15)
				)
				(justify left bottom)
			)
		)
		(fp_text user "License: Apache-2.0"
			(at -1.8 6.8 90)
			(layer "F.Fab")
			(effects
				(font
					(size 0.7 0.7)
					(thickness 0.15)
				)
				(justify left bottom)
			)
		)
		(fp_text user "${REFERENCE}"
			(at 0 0.025 270)
			(layer "F.Fab")
			(effects
				(font
					(size 0.7 0.7)
					(thickness 0.15)
				)
				(justify right top)
			)
		)
		(pad "1" smd roundrect
			(at -1.1 -0.951 90)
			(size 1 0.6)
			(layers "F.Cu" "F.Mask" "F.Paste")
			(roundrect_rratio 0.15)
			(net 124 "/USB-PD/FAULT")
			(pinfunction "G")
			(pintype "input")
		)
		(pad "2" smd roundrect
			(at -1.1 0.949 90)
			(size 1 0.6)
			(layers "F.Cu" "F.Mask" "F.Paste")
			(roundrect_rratio 0.15)
			(net 66 "GND")
			(pinfunction "S")
			(pintype "passive")
		)
		(pad "3" smd roundrect
			(at 1.1 -0.0005 90)
			(size 1 0.6)
			(layers "F.Cu" "F.Mask" "F.Paste")
			(roundrect_rratio 0.15)
			(net 173 "/USB-PD/~{FAULT}")
			(pinfunction "D")
			(pintype "passive")
		)
	)
	(footprint "antmicro-footprints:SOT-23-6"
		(layer "F.Cu")
		(at 141 119.902999 90)
		(property "Reference" "U4"
			(at 0.502999 -3.4 180)
			(layer "F.SilkS")
			(effects
				(font
					(size 0.7 0.7)
					(thickness 0.15)
				)
				(justify left bottom)
			)
		)
		(property "Value" "LTC4412IS6"
			(at -1.749999 2.693 90)
			(layer "F.Fab")
			(effects
				(font
					(size 0.7 0.7)
					(thickness 0.15)
				)
				(justify left bottom)
			)
		)
		(property "Datasheet" "https://www.analog.com/media/en/technical-documentation/data-sheets/4412fb.pdf"
			(at 0 -0.057 90)
			(layer "F.Fab")
			(hide yes)
			(effects
				(font
					(size 1.27 1.27)
					(thickness 0.15)
				)
			)
		)
		(property "Description" "Ideal diode controller"
			(at 0 -0.057 90)
			(layer "F.Fab")
			(hide yes)
			(effects
				(font
					(size 1.27 1.27)
					(thickness 0.15)
				)
			)
		)
		(property "MPN" "LTC4412IS6#TRMPBF"
			(at 0 0 90)
			(unlocked yes)
			(layer "F.Fab")
			(hide yes)
			(effects
				(font
					(size 1 1)
					(thickness 0.15)
				)
			)
		)
		(property "Manufacturer" "Analog Devices"
			(at 0 0 90)
			(unlocked yes)
			(layer "F.Fab")
			(hide yes)
			(effects
				(font
					(size 1 1)
					(thickness 0.15)
				)
			)
		)
		(property "Author" "Antmicro"
			(at 0 0 90)
			(unlocked yes)
			(layer "F.Fab")
			(hide yes)
			(effects
				(font
					(size 1 1)
					(thickness 0.15)
				)
			)
		)
		(property "License" "Apache-2.0"
			(at 0 0 90)
			(unlocked yes)
			(layer "F.Fab")
			(hide yes)
			(effects
				(font
					(size 1 1)
					(thickness 0.15)
				)
			)
		)
		(sheetname "/Power/Ideal-diode-1/")
		(sheetfile "ideal-diode.kicad_sch")
		(attr smd)
		(fp_line
			(start 1.45 -0.757)
			(end 1.45 -0.457)
			(stroke
				(width 0.12)
				(type solid)
			)
			(layer "F.SilkS")
		)
		(fp_line
			(start 1.3 -0.757)
			(end 1.45 -0.757)
			(stroke
				(width 0.12)
				(type solid)
			)
			(layer "F.SilkS")
		)
		(fp_line
			(start -1.3 -0.757)
			(end -1.45 -0.757)
			(stroke
				(width 0.12)
				(type solid)
			)
			(layer "F.SilkS")
		)
		(fp_line
			(start -1.45 -0.757)
			(end -1.45 -0.457)
			(stroke
				(width 0.12)
				(type solid)
			)
			(layer "F.SilkS")
		)
		(fp_line
			(start 1.45 0.643)
			(end 1.45 0.343)
			(stroke
				(width 0.12)
				(type solid)
			)
			(layer "F.SilkS")
		)
		(fp_line
			(start 1.3 0.643)
			(end 1.45 0.643)
			(stroke
				(width 0.12)
				(type solid)
			)
			(layer "F.SilkS")
		)
		(fp_line
			(start -1.45 0.643)
			(end -1.45 0.343)
			(stroke
				(width 0.12)
				(type solid)
			)
			(layer "F.SilkS")
		)
		(fp_rect
			(start -1.55 -1.85)
			(end 1.55 1.75)
			(stroke
				(width 0.05)
				(type solid)
			)
			(fill no)
			(layer "F.CrtYd")
		)
		(fp_line
			(start 1.5 -0.757)
			(end 1.5 0.643)
			(stroke
				(width 0.1)
				(type solid)
			)
			(layer "F.Fab")
		)
		(fp_line
			(start -1.5 -0.757)
			(end 1.5 -0.757)
			(stroke
				(width 0.1)
				(type solid)
			)
			(layer "F.Fab")
		)
		(fp_line
			(start 1.5 0.643)
			(end -1.5 0.643)
			(stroke
				(width 0.1)
				(type solid)
			)
			(layer "F.Fab")
		)
		(fp_line
			(start -1.5 0.643)
			(end -1.5 -0.757)
			(stroke
				(width 0.1)
				(type solid)
			)
			(layer "F.Fab")
		)
		(fp_text user "."
			(at -1.4 1.143001 90)
			(layer "F.SilkS")
			(effects
				(font
					(size 1 1)
					(thickness 0.15)
				)
			)
		)
		(fp_text user "License: Apache-2.0"
			(at -1.75 6.5 90)
			(layer "F.Fab")
			(effects
				(font
					(size 0.7 0.7)
					(thickness 0.15)
				)
				(justify left bottom)
			)
		)
		(fp_text user "${REFERENCE}"
			(at 0 -0.05 90)
			(layer "F.Fab")
			(effects
				(font
					(size 0.7 0.7)
					(thickness 0.15)
				)
				(justify left bottom)
			)
		)
		(fp_text user "Author: Antmicro"
			(at -1.829 5.25 90)
			(layer "F.Fab")
			(effects
				(font
					(size 0.7 0.7)
					(thickness 0.15)
				)
				(justify left bottom)
			)
		)
		(pad "1" smd roundrect
			(at -0.954 1.1 90)
			(size 0.55 1)
			(layers "F.Cu" "F.Mask" "F.Paste")
			(roundrect_rratio 0.15)
			(net 118 "/Power/Ideal-diode-1/VIN")
			(pinfunction "IN")
			(pintype "power_in")
		)
		(pad "2" smd roundrect
			(at -0.003 1.1 90)
			(size 0.55 1)
			(layers "F.Cu" "F.Mask" "F.Paste")
			(roundrect_rratio 0.15)
			(net 66 "GND")
			(pinfunction "GND")
			(pintype "power_in")
		)
		(pad "3" smd roundrect
			(at 0.947 1.1 90)
			(size 0.55 1)
			(layers "F.Cu" "F.Mask" "F.Paste")
			(roundrect_rratio 0.15)
			(net 66 "GND")
			(pinfunction "CTL")
			(pintype "input")
		)
		(pad "4" smd roundrect
			(at 0.947 -1.214 90)
			(size 0.55 1)
			(layers "F.Cu" "F.Mask" "F.Paste")
			(roundrect_rratio 0.15)
			(net 163 "unconnected-(U4-STAT-Pad4)")
			(pinfunction "STAT")
			(pintype "output+no_connect")
		)
		(pad "5" smd roundrect
			(at -0.003 -1.214 90)
			(size 0.55 1)
			(layers "F.Cu" "F.Mask" "F.Paste")
			(roundrect_rratio 0.15)
			(net 104 "Net-(Q1-G)")
			(pinfunction "GATE")
			(pintype "output")
		)
		(pad "6" smd roundrect
			(at -0.954 -1.214 90)
			(size 0.55 1)
			(layers "F.Cu" "F.Mask" "F.Paste")
			(roundrect_rratio 0.15)
			(net 87 "+12V")
			(pinfunction "SENSE")
			(pintype "input")
		)
	)
	(footprint "antmicro-footprints:C_Pol_Vishay-T59-EE"
		(layer "F.Cu")
		(at 138.5 83.499998 180)
		(property "Reference" "C44"
			(at -5.1 -0.300002 180)
			(layer "F.SilkS")
			(effects
				(font
					(size 0.7 0.7)
					(thickness 0.15)
				)
				(justify left bottom)
			)
		)
		(property "Value" "C_Pol_150u_30V_Vishay-T59-EE"
			(at -5.08 5.08 180)
			(unlocked yes)
			(layer "F.Fab")
			(effects
				(font
					(size 0.7 0.7)
					(thickness 0.15)
				)
				(justify left bottom)
			)
		)
		(property "Datasheet" "https://www.vishay.com/docs/40191/t59.pdf"
			(at 0 0 0)
			(layer "F.Fab")
			(hide yes)
			(effects
				(font
					(size 1.27 1.27)
					(thickness 0.15)
				)
			)
		)
		(property "Description" "Tantalum Capacitors - Polymer 150uF 30volts 20% 75mohms maxESR"
			(at 0 0 0)
			(layer "F.Fab")
			(hide yes)
			(effects
				(font
					(size 1.27 1.27)
					(thickness 0.15)
				)
			)
		)
		(property "MPN" "T59EE157M030C0075"
			(at 0 0 180)
			(unlocked yes)
			(layer "F.Fab")
			(hide yes)
			(effects
				(font
					(size 1 1)
					(thickness 0.15)
				)
			)
		)
		(property "Manufacturer" "Vishay"
			(at 0 0 180)
			(unlocked yes)
			(layer "F.Fab")
			(hide yes)
			(effects
				(font
					(size 1 1)
					(thickness 0.15)
				)
			)
		)
		(property "Voltage" "30V"
			(at 0 0 180)
			(unlocked yes)
			(layer "F.Fab")
			(hide yes)
			(effects
				(font
					(size 1 1)
					(thickness 0.15)
				)
			)
		)
		(property "Val" "150u"
			(at 0 0 180)
			(unlocked yes)
			(layer "F.Fab")
			(hide yes)
			(effects
				(font
					(size 1 1)
					(thickness 0.15)
				)
			)
		)
		(property "Author" "Antmicro"
			(at 0 0 180)
			(unlocked yes)
			(layer "F.Fab")
			(hide yes)
			(effects
				(font
					(size 1 1)
					(thickness 0.15)
				)
			)
		)
		(property "License" "Apache-2.0"
			(at 0 0 180)
			(unlocked yes)
			(layer "F.Fab")
			(hide yes)
			(effects
				(font
					(size 1 1)
					(thickness 0.15)
				)
			)
		)
		(property "Dielectric" "template_dielectric"
			(at 0 0 180)
			(unlocked yes)
			(layer "F.Fab")
			(hide yes)
			(effects
				(font
					(size 1 1)
					(thickness 0.15)
				)
			)
		)
		(sheetname "/USB-PD/")
		(sheetfile "usb-pd.kicad_sch")
		(attr smd)
		(fp_line
			(start -2 2.25)
			(end 2 2.25)
			(stroke
				(width 0.15)
				(type solid)
			)
			(layer "F.SilkS")
		)
		(fp_line
			(start -2 -2.25)
			(end 2 -2.25)
			(stroke
				(width 0.15)
				(type solid)
			)
			(layer "F.SilkS")
		)
		(fp_line
			(start -3.5 -2.8)
			(end -3.5 -3.2)
			(stroke
				(width 0.15)
				(type solid)
			)
			(layer "F.SilkS")
		)
		(fp_line
			(start -3.7 -3)
			(end -3.3 -3)
			(stroke
				(width 0.15)
				(type solid)
			)
			(layer "F.SilkS")
		)
		(fp_rect
			(start -4.9 -2.9)
			(end 4.9 2.9)
			(stroke
				(width 0.05)
				(type solid)
			)
			(fill no)
			(layer "F.CrtYd")
		)
		(fp_rect
			(start -3.75 -2.25)
			(end 3.75 2.25)
			(stroke
				(width 0.15)
				(type solid)
			)
			(fill no)
			(layer "F.Fab")
		)
		(fp_text user "Author: Antmicro"
			(at -5.079999 7.08 0)
			(layer "F.Fab")
			(effects
				(font
					(size 0.7 0.7)
					(thickness 0.15)
				)
				(justify right top)
			)
		)
		(fp_text user "License: Apache-2.0"
			(at -5.08 9.48 0)
			(layer "F.Fab")
			(effects
				(font
					(size 0.7 0.7)
					(thickness 0.15)
				)
				(justify right top)
			)
		)
		(fp_text user "${REFERENCE}"
			(at 0 -0.175 180)
			(layer "F.Fab")
			(effects
				(font
					(size 0.7 0.7)
					(thickness 0.15)
				)
				(justify left bottom)
			)
		)
		(pad "1" smd trapezoid
			(at -3.4 0 180)
			(size 2.5 5.3)
			(layers "F.Cu" "F.Mask" "F.Paste")
			(net 115 "/USB-PD/VCC")
			(pintype "passive")
		)
		(pad "2" smd trapezoid
			(at 3.4 0 180)
			(size 2.5 5.3)
			(layers "F.Cu" "F.Mask" "F.Paste")
			(net 66 "GND")
			(pintype "passive")
		)
	)
)
